# T6G (Grand Teton) — schematic netlist excerpt (pin names and nets, part order shuffled) for the footprints in the layout excerpt that follows; sources: Cadence DE-HDL packaged netlist, KiCad conversion of 04192023_DAF0TMB3IC0_F0TG_MB_C_brd_V02_OCP.brd

PR477  Q_RES  0 5% CHIP  pkg 0402LF  page 209 : A = P3V3_AUX ; B = PVDD18_S5_P0_VCC
R468  Q_RES  33 5% CHIP  pkg 0402LF  page 29 : A = ESPI_CPU0_D0 ; B = ESPI_CPU0_R_D0
R1109  Q_RES  0 5% CHIP  pkg 0201LF  page 309 : A = SMB_RT_CPU0_P3_R_SCL ; B = SMB_RT_CPU0_P3_R2_SCL

(kicad_pcb
	(version 20260206)
	(generator "pcbnew")
	(generator_version "10.0")
	(general
		(thickness 1.6)
		(legacy_teardrops no)
	)
	(paper "A4")
	(title_block
		(title "04192023_DAF0TMB3IC0_F0TG_MB_C_brd_V02_OCP.brd")
		(comment 1 "Grand Teton / footprints 7815-7817 of 8354")
	)
	(layers
		(0 "F.Cu" signal "TOP")
		(4 "In1.Cu" signal "GND")
		(6 "In2.Cu" signal "IN1")
		(8 "In3.Cu" signal "GND1")
		(10 "In4.Cu" signal "IN2")
		(12 "In5.Cu" signal "GND2")
		(14 "In6.Cu" signal "IN3")
		(16 "In7.Cu" signal "GND3")
		(18 "In8.Cu" signal "VCC")
		(20 "In9.Cu" signal "VCC1")
		(22 "In10.Cu" signal "GND4")
		(24 "In11.Cu" signal "IN4")
		(26 "In12.Cu" signal "GND5")
		(28 "In13.Cu" signal "IN5")
		(30 "In14.Cu" signal "GND6")
		(32 "In15.Cu" signal "IN6")
		(34 "In16.Cu" signal "GND7")
		(2 "B.Cu" signal "BOTTOM")
		(9 "F.Adhes" user "F.Adhesive")
		(11 "B.Adhes" user "B.Adhesive")
		(13 "F.Paste" user "Package Geometry/Pastemask Top")
		(15 "B.Paste" user "Package Geometry/Pastemask Bottom")
		(5 "F.SilkS" user "Ref Des/Silkscreen Top")
		(7 "B.SilkS" user "Ref Des/Silkscreen Bottom")
		(1 "F.Mask" user "Board Geometry/Soldermask Top")
		(3 "B.Mask" user "Board Geometry/Soldermask Bottom")
		(17 "Dwgs.User" user "User.Drawings")
		(19 "Cmts.User" user "User.Comments")
		(21 "Eco1.User" user "User.Eco1")
		(23 "Eco2.User" user "User.Eco2")
		(25 "Edge.Cuts" user "Board Geometry/Outline")
		(27 "Margin" user)
		(31 "F.CrtYd" user "Package Geometry/Place Bound Top")
		(29 "B.CrtYd" user "Package Geometry/Place Bound Bottom")
		(35 "F.Fab" user "Ref Des/Assembly Top")
		(33 "B.Fab" user "Ref Des/Assembly Bottom")
	)
	(footprint ""
		(layer "B.Cu")
		(at 331.639164 -136.474962 180)
		(property "Reference" "PR477"
			(at 0 0 0)
			(layer "B.SilkS")
			(hide yes)
			(effects
				(font
					(size 1.27 1.27)
				)
				(justify mirror)
			)
		)
		(property "Value" ""
			(at 0 0 0)
			(layer "B.Fab")
			(effects
				(font
					(size 1.27 1.27)
				)
				(justify mirror)
			)
		)
		(duplicate_pad_numbers_are_jumpers no)
		(fp_line
			(start 0.7874 0.4064)
			(end 0.7874 -0.4064)
			(stroke
				(width 0.1524)
				(type default)
			)
			(layer "B.SilkS")
		)
		(fp_line
			(start 0.7874 -0.4064)
			(end -0.7874 -0.4064)
			(stroke
				(width 0.1524)
				(type default)
			)
			(layer "B.SilkS")
		)
		(fp_line
			(start -0.7874 0.4064)
			(end 0.7874 0.4064)
			(stroke
				(width 0.1524)
				(type default)
			)
			(layer "B.SilkS")
		)
		(fp_line
			(start -0.7874 -0.4064)
			(end -0.7874 0.4064)
			(stroke
				(width 0.1524)
				(type default)
			)
			(layer "B.SilkS")
		)
		(fp_line
			(start 0.67945 0.3048)
			(end 0.67945 -0.305054)
			(stroke
				(width 0.1)
				(type default)
			)
			(layer "B.Fab")
		)
		(fp_line
			(start 0.67945 -0.305054)
			(end 0.12065 -0.305054)
			(stroke
				(width 0.1)
				(type default)
			)
			(layer "B.Fab")
		)
		(fp_line
			(start 0.12065 0.3048)
			(end 0.67945 0.3048)
			(stroke
				(width 0.1)
				(type default)
			)
			(layer "B.Fab")
		)
		(fp_line
			(start 0.12065 0.2794)
			(end 0.12065 0.3048)
			(stroke
				(width 0.1)
				(type default)
			)
			(layer "B.Fab")
		)
		(fp_line
			(start 0.12065 -0.2794)
			(end -0.12065 -0.2794)
			(stroke
				(width 0.1)
				(type default)
			)
			(layer "B.Fab")
		)
		(fp_line
			(start 0.12065 -0.305054)
			(end 0.12065 -0.2794)
			(stroke
				(width 0.1)
				(type default)
			)
			(layer "B.Fab")
		)
		(fp_line
			(start -0.120396 0.3048)
			(end -0.120396 0.2794)
			(stroke
				(width 0.1)
				(type default)
			)
			(layer "B.Fab")
		)
		(fp_line
			(start -0.120396 0.2794)
			(end 0.12065 0.2794)
			(stroke
				(width 0.1)
				(type default)
			)
			(layer "B.Fab")
		)
		(fp_line
			(start -0.12065 -0.2794)
			(end -0.12065 -0.3048)
			(stroke
				(width 0.1)
				(type default)
			)
			(layer "B.Fab")
		)
		(fp_line
			(start -0.12065 -0.3048)
			(end -0.67945 -0.3048)
			(stroke
				(width 0.1)
				(type default)
			)
			(layer "B.Fab")
		)
		(fp_line
			(start -0.67945 0.3048)
			(end -0.120396 0.3048)
			(stroke
				(width 0.1)
				(type default)
			)
			(layer "B.Fab")
		)
		(fp_line
			(start -0.67945 -0.3048)
			(end -0.67945 0.3048)
			(stroke
				(width 0.1)
				(type default)
			)
			(layer "B.Fab")
		)
		(pad "1" smd circle
			(at 0.40005 0)
			(size 0 0)
			(layers "B.Cu" "B.Mask" "B.Paste")
			(net "P3V3_AUX")
		)
		(pad "2" smd circle
			(at -0.40005 0)
			(size 0 0)
			(layers "B.Cu" "B.Mask" "B.Paste")
			(net "PVDD18_S5_P0_VCC")
		)
	)
	(footprint ""
		(layer "B.Cu")
		(at 393.602718 -323.692012)
		(property "Reference" "R468"
			(at 0 0 0)
			(layer "B.SilkS")
			(hide yes)
			(effects
				(font
					(size 1.27 1.27)
				)
				(justify mirror)
			)
		)
		(property "Value" ""
			(at 0 0 0)
			(layer "B.Fab")
			(effects
				(font
					(size 1.27 1.27)
				)
				(justify mirror)
			)
		)
		(duplicate_pad_numbers_are_jumpers no)
		(fp_line
			(start -0.7874 -0.4064)
			(end -0.7874 0.4064)
			(stroke
				(width 0.1524)
				(type default)
			)
			(layer "B.SilkS")
		)
		(fp_line
			(start -0.7874 0.4064)
			(end 0.7874 0.4064)
			(stroke
				(width 0.1524)
				(type default)
			)
			(layer "B.SilkS")
		)
		(fp_line
			(start 0.7874 -0.4064)
			(end -0.7874 -0.4064)
			(stroke
				(width 0.1524)
				(type default)
			)
			(layer "B.SilkS")
		)
		(fp_line
			(start 0.7874 0.4064)
			(end 0.7874 -0.4064)
			(stroke
				(width 0.1524)
				(type default)
			)
			(layer "B.SilkS")
		)
		(fp_line
			(start -0.67945 -0.3048)
			(end -0.67945 0.3048)
			(stroke
				(width 0.1)
				(type default)
			)
			(layer "B.Fab")
		)
		(fp_line
			(start -0.67945 0.3048)
			(end -0.120396 0.3048)
			(stroke
				(width 0.1)
				(type default)
			)
			(layer "B.Fab")
		)
		(fp_line
			(start -0.12065 -0.3048)
			(end -0.67945 -0.3048)
			(stroke
				(width 0.1)
				(type default)
			)
			(layer "B.Fab")
		)
		(fp_line
			(start -0.12065 -0.2794)
			(end -0.12065 -0.3048)
			(stroke
				(width 0.1)
				(type default)
			)
			(layer "B.Fab")
		)
		(fp_line
			(start -0.120396 0.2794)
			(end 0.12065 0.2794)
			(stroke
				(width 0.1)
				(type default)
			)
			(layer "B.Fab")
		)
		(fp_line
			(start -0.120396 0.3048)
			(end -0.120396 0.2794)
			(stroke
				(width 0.1)
				(type default)
			)
			(layer "B.Fab")
		)
		(fp_line
			(start 0.12065 -0.305054)
			(end 0.12065 -0.2794)
			(stroke
				(width 0.1)
				(type default)
			)
			(layer "B.Fab")
		)
		(fp_line
			(start 0.12065 -0.2794)
			(end -0.12065 -0.2794)
			(stroke
				(width 0.1)
				(type default)
			)
			(layer "B.Fab")
		)
		(fp_line
			(start 0.12065 0.2794)
			(end 0.12065 0.3048)
			(stroke
				(width 0.1)
				(type default)
			)
			(layer "B.Fab")
		)
		(fp_line
			(start 0.12065 0.3048)
			(end 0.67945 0.3048)
			(stroke
				(width 0.1)
				(type default)
			)
			(layer "B.Fab")
		)
		(fp_line
			(start 0.67945 -0.305054)
			(end 0.12065 -0.305054)
			(stroke
				(width 0.1)
				(type default)
			)
			(layer "B.Fab")
		)
		(fp_line
			(start 0.67945 0.3048)
			(end 0.67945 -0.305054)
			(stroke
				(width 0.1)
				(type default)
			)
			(layer "B.Fab")
		)
		(pad "1" smd circle
			(at 0.40005 0 180)
			(size 0 0)
			(layers "B.Cu" "B.Mask" "B.Paste")
			(net "ESPI_CPU0_D0")
		)
		(pad "2" smd circle
			(at -0.40005 0 180)
			(size 0 0)
			(layers "B.Cu" "B.Mask" "B.Paste")
			(net "ESPI_CPU0_R_D0")
		)
	)
	(footprint ""
		(layer "B.Cu")
		(at 233.172 -336.296 180)
		(property "Reference" "R1109"
			(at 0 0 0)
			(layer "B.SilkS")
			(hide yes)
			(effects
				(font
					(size 1.27 1.27)
				)
				(justify mirror)
			)
		)
		(property "Value" ""
			(at 0 0 0)
			(layer "B.Fab")
			(effects
				(font
					(size 1.27 1.27)
				)
				(justify mirror)
			)
		)
		(duplicate_pad_numbers_are_jumpers no)
		(fp_line
			(start 0.32512 0.175006)
			(end 0.32512 -0.175006)
			(stroke
				(width 0.1)
				(type default)
			)
			(layer "B.Fab")
		)
		(fp_line
			(start 0.32512 -0.175006)
			(end -0.32512 -0.175006)
			(stroke
				(width 0.1)
				(type default)
			)
			(layer "B.Fab")
		)
		(fp_line
			(start -0.32512 0.175006)
			(end 0.32512 0.175006)
			(stroke
				(width 0.1)
				(type default)
			)
			(layer "B.Fab")
		)
		(fp_line
			(start -0.32512 -0.175006)
			(end -0.32512 0.175006)
			(stroke
				(width 0.1)
				(type default)
			)
			(layer "B.Fab")
		)
		(pad "1" smd rect
			(at 0.2667 0)
			(size 0.3048 0.381)
			(layers "B.Cu" "B.Mask" "B.Paste")
			(net "SMB_RT_CPU0_P3_R_SCL")
		)
		(pad "2" smd rect
			(at -0.2667 0 180)
			(size 0.3048 0.381)
			(layers "B.Cu" "B.Mask" "B.Paste")
			(net "SMB_RT_CPU0_P3_R2_SCL")
		)
	)
)
